(kicad_pcb
	(version 20260206)
	(generator "pcbnew")
	(generator_version "10.0")
	(general
		(thickness 1.6)
		(legacy_teardrops no)
	)
	(paper "A4")
	(title_block
		(title "04192023_DAF0TMB3IC0_F0TG_MB_C_brd_V02_OCP.brd")
		(comment 1 "Grand Teton / footprints 5905-5911 of 8354")
	)
	(layers
		(0 "F.Cu" signal "TOP")
		(4 "In1.Cu" signal "GND")
		(6 "In2.Cu" signal "IN1")
		(8 "In3.Cu" signal "GND1")
		(10 "In4.Cu" signal "IN2")
		(12 "In5.Cu" signal "GND2")
		(14 "In6.Cu" signal "IN3")
		(16 "In7.Cu" signal "GND3")
		(18 "In8.Cu" signal "VCC")
		(20 "In9.Cu" signal "VCC1")
		(22 "In10.Cu" signal "GND4")
		(24 "In11.Cu" signal "IN4")
		(26 "In12.Cu" signal "GND5")
		(28 "In13.Cu" signal "IN5")
		(30 "In14.Cu" signal "GND6")
		(32 "In15.Cu" signal "IN6")
		(34 "In16.Cu" signal "GND7")
		(2 "B.Cu" signal "BOTTOM")
		(9 "F.Adhes" user "F.Adhesive")
		(11 "B.Adhes" user "B.Adhesive")
		(13 "F.Paste" user "Package Geometry/Pastemask Top")
		(15 "B.Paste" user "Package Geometry/Pastemask Bottom")
		(5 "F.SilkS" user "Ref Des/Silkscreen Top")
		(7 "B.SilkS" user "Ref Des/Silkscreen Bottom")
		(1 "F.Mask" user "Board Geometry/Soldermask Top")
		(3 "B.Mask" user "Board Geometry/Soldermask Bottom")
		(17 "Dwgs.User" user "User.Drawings")
		(19 "Cmts.User" user "User.Comments")
		(21 "Eco1.User" user "User.Eco1")
		(23 "Eco2.User" user "User.Eco2")
		(25 "Edge.Cuts" user "Board Geometry/Outline")
		(27 "Margin" user)
		(31 "F.CrtYd" user "Package Geometry/Place Bound Top")
		(29 "B.CrtYd" user "Package Geometry/Place Bound Bottom")
		(35 "F.Fab" user "Ref Des/Assembly Top")
		(33 "B.Fab" user "Ref Des/Assembly Bottom")
	)
	(footprint ""
		(layer "B.Cu")
		(at 348.101158 -271.878552 90)
		(property "Reference" "C2233"
			(at 0 0 90)
			(layer "B.SilkS")
			(hide yes)
			(effects
				(font
					(size 1.27 1.27)
				)
				(justify mirror)
			)
		)
		(property "Value" ""
			(at 0 0 90)
			(layer "B.Fab")
			(effects
				(font
					(size 1.27 1.27)
				)
				(justify mirror)
			)
		)
		(duplicate_pad_numbers_are_jumpers no)
		(fp_line
			(start 0.7874 -0.4064)
			(end -0.7874 -0.4064)
			(stroke
				(width 0.1524)
				(type default)
			)
			(layer "B.SilkS")
		)
		(fp_line
			(start -0.7874 -0.4064)
			(end -0.7874 0.4064)
			(stroke
				(width 0.1524)
				(type default)
			)
			(layer "B.SilkS")
		)
		(fp_line
			(start 0.7874 0.4064)
			(end 0.7874 -0.4064)
			(stroke
				(width 0.1524)
				(type default)
			)
			(layer "B.SilkS")
		)
		(fp_line
			(start -0.7874 0.4064)
			(end 0.7874 0.4064)
			(stroke
				(width 0.1524)
				(type default)
			)
			(layer "B.SilkS")
		)
		(fp_line
			(start 0.67945 -0.305054)
			(end 0.12065 -0.305054)
			(stroke
				(width 0.1)
				(type default)
			)
			(layer "B.Fab")
		)
		(fp_line
			(start 0.12065 -0.305054)
			(end 0.12065 -0.2794)
			(stroke
				(width 0.1)
				(type default)
			)
			(layer "B.Fab")
		)
		(fp_line
			(start -0.12065 -0.3048)
			(end -0.67945 -0.3048)
			(stroke
				(width 0.1)
				(type default)
			)
			(layer "B.Fab")
		)
		(fp_line
			(start -0.67945 -0.3048)
			(end -0.67945 0.3048)
			(stroke
				(width 0.1)
				(type default)
			)
			(layer "B.Fab")
		)
		(fp_line
			(start 0.12065 -0.2794)
			(end -0.12065 -0.2794)
			(stroke
				(width 0.1)
				(type default)
			)
			(layer "B.Fab")
		)
		(fp_line
			(start -0.12065 -0.2794)
			(end -0.12065 -0.3048)
			(stroke
				(width 0.1)
				(type default)
			)
			(layer "B.Fab")
		)
		(fp_line
			(start 0.12065 0.2794)
			(end 0.12065 0.3048)
			(stroke
				(width 0.1)
				(type default)
			)
			(layer "B.Fab")
		)
		(fp_line
			(start -0.120396 0.2794)
			(end 0.12065 0.2794)
			(stroke
				(width 0.1)
				(type default)
			)
			(layer "B.Fab")
		)
		(fp_line
			(start 0.67945 0.3048)
			(end 0.67945 -0.305054)
			(stroke
				(width 0.1)
				(type default)
			)
			(layer "B.Fab")
		)
		(fp_line
			(start 0.12065 0.3048)
			(end 0.67945 0.3048)
			(stroke
				(width 0.1)
				(type default)
			)
			(layer "B.Fab")
		)
		(fp_line
			(start -0.120396 0.3048)
			(end -0.120396 0.2794)
			(stroke
				(width 0.1)
				(type default)
			)
			(layer "B.Fab")
		)
		(fp_line
			(start -0.67945 0.3048)
			(end -0.120396 0.3048)
			(stroke
				(width 0.1)
				(type default)
			)
			(layer "B.Fab")
		)
		(pad "1" smd circle
			(at 0.40005 0 270)
			(size 0 0)
			(layers "B.Cu" "B.Mask" "B.Paste")
			(net "PVDDCR_CPU1_P0")
		)
		(pad "2" smd circle
			(at -0.40005 0 270)
			(size 0 0)
			(layers "B.Cu" "B.Mask" "B.Paste")
			(net "GND")
		)
	)
	(footprint ""
		(layer "B.Cu")
		(at 77.973682 -328.24547 -90)
		(property "Reference" "PC388"
			(at 9.98347 -1.374648 270)
			(unlocked yes)
			(layer "B.SilkS")
			(effects
				(font
					(size 0.7874 0.5842)
					(thickness 0.1524)
				)
				(justify left mirror)
			)
		)
		(property "Value" ""
			(at 0 0 90)
			(layer "B.Fab")
			(effects
				(font
					(size 1.27 1.27)
				)
				(justify mirror)
			)
		)
		(duplicate_pad_numbers_are_jumpers no)
		(fp_line
			(start -4.533392 2.249932)
			(end 4.533392 2.249932)
			(stroke
				(width 0.1524)
				(type default)
			)
			(layer "B.SilkS")
		)
		(fp_line
			(start 4.533392 2.249932)
			(end 4.533392 -2.249932)
			(stroke
				(width 0.1524)
				(type default)
			)
			(layer "B.SilkS")
		)
		(fp_line
			(start -4.533392 -2.249932)
			(end -4.533392 2.249932)
			(stroke
				(width 0.1524)
				(type default)
			)
			(layer "B.SilkS")
		)
		(fp_line
			(start 4.533392 -2.249932)
			(end -4.533392 -2.249932)
			(stroke
				(width 0.1524)
				(type default)
			)
			(layer "B.SilkS")
		)
		(fp_rect
			(start 5.39242 2.326132)
			(end 4.533392 -2.326132)
			(stroke
				(width 0)
				(type default)
			)
			(fill yes)
			(layer "B.SilkS")
		)
		(fp_line
			(start -3.750056 2.249932)
			(end 3.750056 2.249932)
			(stroke
				(width 0.1)
				(type default)
			)
			(layer "B.Fab")
		)
		(fp_line
			(start 3.750056 2.249932)
			(end 3.750056 -2.249932)
			(stroke
				(width 0.1)
				(type default)
			)
			(layer "B.Fab")
		)
		(fp_line
			(start -3.750056 -2.249932)
			(end -3.750056 2.249932)
			(stroke
				(width 0.1)
				(type default)
			)
			(layer "B.Fab")
		)
		(fp_line
			(start 3.750056 -2.249932)
			(end -3.750056 -2.249932)
			(stroke
				(width 0.1)
				(type default)
			)
			(layer "B.Fab")
		)
		(fp_text user "-"
			(at -4.712462 1.477264 270)
			(unlocked yes)
			(layer "B.SilkS")
			(effects
				(font
					(size 1.905 1.4224)
					(thickness 0.1524)
				)
				(justify left mirror)
			)
		)
		(fp_text user "+"
			(at 6.265418 0.05207 180)
			(unlocked yes)
			(layer "B.SilkS")
			(effects
				(font
					(size 1.905 1.4224)
					(thickness 0.1524)
				)
				(justify left mirror)
			)
		)
		(fp_text user "+"
			(at 6.322314 0.786384 180)
			(unlocked yes)
			(layer "B.Fab")
			(effects
				(font
					(size 1.905 1.4224)
					(thickness 0.1524)
				)
				(justify left mirror)
			)
		)
		(fp_text user "-"
			(at -4.8514 -0.14605 270)
			(unlocked yes)
			(layer "B.Fab")
			(effects
				(font
					(size 1.905 1.4224)
					(thickness 0.1524)
				)
				(justify left mirror)
			)
		)
		(pad "1" smd rect
			(at 3.199892 0 90)
			(size 2.413 2.8194)
			(layers "B.Cu" "B.Mask" "B.Paste")
			(net "PVDDCR_CPU1_P1")
		)
		(pad "2" smd rect
			(at -3.199892 0 90)
			(size 2.413 2.8194)
			(layers "B.Cu" "B.Mask" "B.Paste")
			(net "GND")
		)
	)
	(footprint ""
		(layer "B.Cu")
		(at 403.981158 -329.003152)
		(property "Reference" "R748"
			(at 0 0 0)
			(layer "B.SilkS")
			(hide yes)
			(effects
				(font
					(size 1.27 1.27)
				)
				(justify mirror)
			)
		)
		(property "Value" ""
			(at 0 0 0)
			(layer "B.Fab")
			(effects
				(font
					(size 1.27 1.27)
				)
				(justify mirror)
			)
		)
		(duplicate_pad_numbers_are_jumpers no)
		(fp_line
			(start -0.7874 -0.4064)
			(end -0.7874 0.4064)
			(stroke
				(width 0.1524)
				(type default)
			)
			(layer "B.SilkS")
		)
		(fp_line
			(start -0.7874 0.4064)
			(end 0.7874 0.4064)
			(stroke
				(width 0.1524)
				(type default)
			)
			(layer "B.SilkS")
		)
		(fp_line
			(start 0.7874 -0.4064)
			(end -0.7874 -0.4064)
			(stroke
				(width 0.1524)
				(type default)
			)
			(layer "B.SilkS")
		)
		(fp_line
			(start 0.7874 0.4064)
			(end 0.7874 -0.4064)
			(stroke
				(width 0.1524)
				(type default)
			)
			(layer "B.SilkS")
		)
		(fp_line
			(start -0.67945 -0.3048)
			(end -0.67945 0.3048)
			(stroke
				(width 0.1)
				(type default)
			)
			(layer "B.Fab")
		)
		(fp_line
			(start -0.67945 0.3048)
			(end -0.120396 0.3048)
			(stroke
				(width 0.1)
				(type default)
			)
			(layer "B.Fab")
		)
		(fp_line
			(start -0.12065 -0.3048)
			(end -0.67945 -0.3048)
			(stroke
				(width 0.1)
				(type default)
			)
			(layer "B.Fab")
		)
		(fp_line
			(start -0.12065 -0.2794)
			(end -0.12065 -0.3048)
			(stroke
				(width 0.1)
				(type default)
			)
			(layer "B.Fab")
		)
		(fp_line
			(start -0.120396 0.2794)
			(end 0.12065 0.2794)
			(stroke
				(width 0.1)
				(type default)
			)
			(layer "B.Fab")
		)
		(fp_line
			(start -0.120396 0.3048)
			(end -0.120396 0.2794)
			(stroke
				(width 0.1)
				(type default)
			)
			(layer "B.Fab")
		)
		(fp_line
			(start 0.12065 -0.305054)
			(end 0.12065 -0.2794)
			(stroke
				(width 0.1)
				(type default)
			)
			(layer "B.Fab")
		)
		(fp_line
			(start 0.12065 -0.2794)
			(end -0.12065 -0.2794)
			(stroke
				(width 0.1)
				(type default)
			)
			(layer "B.Fab")
		)
		(fp_line
			(start 0.12065 0.2794)
			(end 0.12065 0.3048)
			(stroke
				(width 0.1)
				(type default)
			)
			(layer "B.Fab")
		)
		(fp_line
			(start 0.12065 0.3048)
			(end 0.67945 0.3048)
			(stroke
				(width 0.1)
				(type default)
			)
			(layer "B.Fab")
		)
		(fp_line
			(start 0.67945 -0.305054)
			(end 0.12065 -0.305054)
			(stroke
				(width 0.1)
				(type default)
			)
			(layer "B.Fab")
		)
		(fp_line
			(start 0.67945 0.3048)
			(end 0.67945 -0.305054)
			(stroke
				(width 0.1)
				(type default)
			)
			(layer "B.Fab")
		)
		(pad "1" smd circle
			(at 0.40005 0 180)
			(size 0 0)
			(layers "B.Cu" "B.Mask" "B.Paste")
			(net "GND")
		)
		(pad "2" smd circle
			(at -0.40005 0 180)
			(size 0 0)
			(layers "B.Cu" "B.Mask" "B.Paste")
			(net "CPU0_ROM_TYPE_SELECT")
		)
	)
	(footprint ""
		(layer "B.Cu")
		(at 364.167166 -261.747762 90)
		(property "Reference" "C3891"
			(at 0 0 90)
			(layer "B.SilkS")
			(hide yes)
			(effects
				(font
					(size 1.27 1.27)
				)
				(justify mirror)
			)
		)
		(property "Value" ""
			(at 0 0 90)
			(layer "B.Fab")
			(effects
				(font
					(size 1.27 1.27)
				)
				(justify mirror)
			)
		)
		(duplicate_pad_numbers_are_jumpers no)
		(fp_line
			(start 0.7874 -0.4064)
			(end -0.7874 -0.4064)
			(stroke
				(width 0.1524)
				(type default)
			)
			(layer "B.SilkS")
		)
		(fp_line
			(start -0.7874 -0.4064)
			(end -0.7874 0.4064)
			(stroke
				(width 0.1524)
				(type default)
			)
			(layer "B.SilkS")
		)
		(fp_line
			(start 0.7874 0.4064)
			(end 0.7874 -0.4064)
			(stroke
				(width 0.1524)
				(type default)
			)
			(layer "B.SilkS")
		)
		(fp_line
			(start -0.7874 0.4064)
			(end 0.7874 0.4064)
			(stroke
				(width 0.1524)
				(type default)
			)
			(layer "B.SilkS")
		)
		(fp_line
			(start 0.67945 -0.305054)
			(end 0.12065 -0.305054)
			(stroke
				(width 0.1)
				(type default)
			)
			(layer "B.Fab")
		)
		(fp_line
			(start 0.12065 -0.305054)
			(end 0.12065 -0.2794)
			(stroke
				(width 0.1)
				(type default)
			)
			(layer "B.Fab")
		)
		(fp_line
			(start -0.12065 -0.3048)
			(end -0.67945 -0.3048)
			(stroke
				(width 0.1)
				(type default)
			)
			(layer "B.Fab")
		)
		(fp_line
			(start -0.67945 -0.3048)
			(end -0.67945 0.3048)
			(stroke
				(width 0.1)
				(type default)
			)
			(layer "B.Fab")
		)
		(fp_line
			(start 0.12065 -0.2794)
			(end -0.12065 -0.2794)
			(stroke
				(width 0.1)
				(type default)
			)
			(layer "B.Fab")
		)
		(fp_line
			(start -0.12065 -0.2794)
			(end -0.12065 -0.3048)
			(stroke
				(width 0.1)
				(type default)
			)
			(layer "B.Fab")
		)
		(fp_line
			(start 0.12065 0.2794)
			(end 0.12065 0.3048)
			(stroke
				(width 0.1)
				(type default)
			)
			(layer "B.Fab")
		)
		(fp_line
			(start -0.120396 0.2794)
			(end 0.12065 0.2794)
			(stroke
				(width 0.1)
				(type default)
			)
			(layer "B.Fab")
		)
		(fp_line
			(start 0.67945 0.3048)
			(end 0.67945 -0.305054)
			(stroke
				(width 0.1)
				(type default)
			)
			(layer "B.Fab")
		)
		(fp_line
			(start 0.12065 0.3048)
			(end 0.67945 0.3048)
			(stroke
				(width 0.1)
				(type default)
			)
			(layer "B.Fab")
		)
		(fp_line
			(start -0.120396 0.3048)
			(end -0.120396 0.2794)
			(stroke
				(width 0.1)
				(type default)
			)
			(layer "B.Fab")
		)
		(fp_line
			(start -0.67945 0.3048)
			(end -0.120396 0.3048)
			(stroke
				(width 0.1)
				(type default)
			)
			(layer "B.Fab")
		)
		(pad "1" smd circle
			(at 0.40005 0 270)
			(size 0 0)
			(layers "B.Cu" "B.Mask" "B.Paste")
			(net "PVDD11_S3_P0")
		)
		(pad "2" smd circle
			(at -0.40005 0 270)
			(size 0 0)
			(layers "B.Cu" "B.Mask" "B.Paste")
			(net "GND")
		)
	)
	(footprint ""
		(layer "B.Cu")
		(at 336.827876 -66.708782 90)
		(property "Reference" "R3093"
			(at 0 0 90)
			(layer "B.SilkS")
			(hide yes)
			(effects
				(font
					(size 1.27 1.27)
				)
				(justify mirror)
			)
		)
		(property "Value" ""
			(at 0 0 90)
			(layer "B.Fab")
			(effects
				(font
					(size 1.27 1.27)
				)
				(justify mirror)
			)
		)
		(duplicate_pad_numbers_are_jumpers no)
		(fp_line
			(start 0.7874 -0.4064)
			(end -0.7874 -0.4064)
			(stroke
				(width 0.1524)
				(type default)
			)
			(layer "B.SilkS")
		)
		(fp_line
			(start -0.7874 -0.4064)
			(end -0.7874 0.4064)
			(stroke
				(width 0.1524)
				(type default)
			)
			(layer "B.SilkS")
		)
		(fp_line
			(start 0.7874 0.4064)
			(end 0.7874 -0.4064)
			(stroke
				(width 0.1524)
				(type default)
			)
			(layer "B.SilkS")
		)
		(fp_line
			(start -0.7874 0.4064)
			(end 0.7874 0.4064)
			(stroke
				(width 0.1524)
				(type default)
			)
			(layer "B.SilkS")
		)
		(fp_line
			(start 0.67945 -0.305054)
			(end 0.12065 -0.305054)
			(stroke
				(width 0.1)
				(type default)
			)
			(layer "B.Fab")
		)
		(fp_line
			(start 0.12065 -0.305054)
			(end 0.12065 -0.2794)
			(stroke
				(width 0.1)
				(type default)
			)
			(layer "B.Fab")
		)
		(fp_line
			(start -0.12065 -0.3048)
			(end -0.67945 -0.3048)
			(stroke
				(width 0.1)
				(type default)
			)
			(layer "B.Fab")
		)
		(fp_line
			(start -0.67945 -0.3048)
			(end -0.67945 0.3048)
			(stroke
				(width 0.1)
				(type default)
			)
			(layer "B.Fab")
		)
		(fp_line
			(start 0.12065 -0.2794)
			(end -0.12065 -0.2794)
			(stroke
				(width 0.1)
				(type default)
			)
			(layer "B.Fab")
		)
		(fp_line
			(start -0.12065 -0.2794)
			(end -0.12065 -0.3048)
			(stroke
				(width 0.1)
				(type default)
			)
			(layer "B.Fab")
		)
		(fp_line
			(start 0.12065 0.2794)
			(end 0.12065 0.3048)
			(stroke
				(width 0.1)
				(type default)
			)
			(layer "B.Fab")
		)
		(fp_line
			(start -0.120396 0.2794)
			(end 0.12065 0.2794)
			(stroke
				(width 0.1)
				(type default)
			)
			(layer "B.Fab")
		)
		(fp_line
			(start 0.67945 0.3048)
			(end 0.67945 -0.305054)
			(stroke
				(width 0.1)
				(type default)
			)
			(layer "B.Fab")
		)
		(fp_line
			(start 0.12065 0.3048)
			(end 0.67945 0.3048)
			(stroke
				(width 0.1)
				(type default)
			)
			(layer "B.Fab")
		)
		(fp_line
			(start -0.120396 0.3048)
			(end -0.120396 0.2794)
			(stroke
				(width 0.1)
				(type default)
			)
			(layer "B.Fab")
		)
		(fp_line
			(start -0.67945 0.3048)
			(end -0.120396 0.3048)
			(stroke
				(width 0.1)
				(type default)
			)
			(layer "B.Fab")
		)
		(pad "1" smd circle
			(at 0.40005 0 270)
			(size 0 0)
			(layers "B.Cu" "B.Mask" "B.Paste")
			(net "LED_PWRGD_PVDDCR_CPU0_P1_R")
		)
		(pad "2" smd circle
			(at -0.40005 0 270)
			(size 0 0)
			(layers "B.Cu" "B.Mask" "B.Paste")
			(net "P3V3_AUX")
		)
	)
	(footprint ""
		(layer "B.Cu")
		(at 162.606228 -386.766562 90)
		(property "Reference" "C391"
			(at 0 0 90)
			(layer "B.SilkS")
			(hide yes)
			(effects
				(font
					(size 1.27 1.27)
				)
				(justify mirror)
			)
		)
		(property "Value" ""
			(at 0 0 90)
			(layer "B.Fab")
			(effects
				(font
					(size 1.27 1.27)
				)
				(justify mirror)
			)
		)
		(duplicate_pad_numbers_are_jumpers no)
		(fp_line
			(start 0.299974 -0.150114)
			(end -0.299974 -0.150114)
			(stroke
				(width 0.1)
				(type default)
			)
			(layer "B.Fab")
		)
		(fp_line
			(start -0.299974 -0.150114)
			(end -0.299974 0.150114)
			(stroke
				(width 0.1)
				(type default)
			)
			(layer "B.Fab")
		)
		(fp_line
			(start 0.299974 0.150114)
			(end 0.299974 -0.150114)
			(stroke
				(width 0.1)
				(type default)
			)
			(layer "B.Fab")
		)
		(fp_line
			(start -0.299974 0.150114)
			(end 0.299974 0.150114)
			(stroke
				(width 0.1)
				(type default)
			)
			(layer "B.Fab")
		)
		(pad "1" smd rect
			(at 0.2667 0 270)
			(size 0.3048 0.381)
			(layers "B.Cu" "B.Mask" "B.Paste")
			(net "P0V9_CPU1_RT2_2A")
		)
		(pad "2" smd rect
			(at -0.2667 0 270)
			(size 0.3048 0.381)
			(layers "B.Cu" "B.Mask" "B.Paste")
			(net "GND")
		)
	)
	(footprint ""
		(layer "B.Cu")
		(at 281.391614 -193.99631)
		(property "Reference" "R92"
			(at 0 0 0)
			(layer "B.SilkS")
			(hide yes)
			(effects
				(font
					(size 1.27 1.27)
				)
				(justify mirror)
			)
		)
		(property "Value" ""
			(at 0 0 0)
			(layer "B.Fab")
			(effects
				(font
					(size 1.27 1.27)
				)
				(justify mirror)
			)
		)
		(duplicate_pad_numbers_are_jumpers no)
		(fp_line
			(start -0.7874 -0.4064)
			(end -0.7874 0.4064)
			(stroke
				(width 0.1524)
				(type default)
			)
			(layer "B.SilkS")
		)
		(fp_line
			(start -0.7874 0.4064)
			(end 0.7874 0.4064)
			(stroke
				(width 0.1524)
				(type default)
			)
			(layer "B.SilkS")
		)
		(fp_line
			(start 0.7874 -0.4064)
			(end -0.7874 -0.4064)
			(stroke
				(width 0.1524)
				(type default)
			)
			(layer "B.SilkS")
		)
		(fp_line
			(start 0.7874 0.4064)
			(end 0.7874 -0.4064)
			(stroke
				(width 0.1524)
				(type default)
			)
			(layer "B.SilkS")
		)
		(fp_line
			(start -0.67945 -0.3048)
			(end -0.67945 0.3048)
			(stroke
				(width 0.1)
				(type default)
			)
			(layer "B.Fab")
		)
		(fp_line
			(start -0.67945 0.3048)
			(end -0.120396 0.3048)
			(stroke
				(width 0.1)
				(type default)
			)
			(layer "B.Fab")
		)
		(fp_line
			(start -0.12065 -0.3048)
			(end -0.67945 -0.3048)
			(stroke
				(width 0.1)
				(type default)
			)
			(layer "B.Fab")
		)
		(fp_line
			(start -0.12065 -0.2794)
			(end -0.12065 -0.3048)
			(stroke
				(width 0.1)
				(type default)
			)
			(layer "B.Fab")
		)
		(fp_line
			(start -0.120396 0.2794)
			(end 0.12065 0.2794)
			(stroke
				(width 0.1)
				(type default)
			)
			(layer "B.Fab")
		)
		(fp_line
			(start -0.120396 0.3048)
			(end -0.120396 0.2794)
			(stroke
				(width 0.1)
				(type default)
			)
			(layer "B.Fab")
		)
		(fp_line
			(start 0.12065 -0.305054)
			(end 0.12065 -0.2794)
			(stroke
				(width 0.1)
				(type default)
			)
			(layer "B.Fab")
		)
		(fp_line
			(start 0.12065 -0.2794)
			(end -0.12065 -0.2794)
			(stroke
				(width 0.1)
				(type default)
			)
			(layer "B.Fab")
		)
		(fp_line
			(start 0.12065 0.2794)
			(end 0.12065 0.3048)
			(stroke
				(width 0.1)
				(type default)
			)
			(layer "B.Fab")
		)
		(fp_line
			(start 0.12065 0.3048)
			(end 0.67945 0.3048)
			(stroke
				(width 0.1)
				(type default)
			)
			(layer "B.Fab")
		)
		(fp_line
			(start 0.67945 -0.305054)
			(end 0.12065 -0.305054)
			(stroke
				(width 0.1)
				(type default)
			)
			(layer "B.Fab")
		)
		(fp_line
			(start 0.67945 0.3048)
			(end 0.67945 -0.305054)
			(stroke
				(width 0.1)
				(type default)
			)
			(layer "B.Fab")
		)
		(pad "1" smd circle
			(at 0.40005 0 180)
			(size 0 0)
			(layers "B.Cu" "B.Mask" "B.Paste")
			(net "P3V3")
		)
		(pad "2" smd circle
			(at -0.40005 0 180)
			(size 0 0)
			(layers "B.Cu" "B.Mask" "B.Paste")
			(net "PWRGD_CHD_CPU0_DIMM")
		)
	)
)
